(kicad_pcb
	(version 20260206)
	(generator "pcbnew")
	(generator_version "10.0")
	(general
		(thickness 1.6)
		(legacy_teardrops no)
	)
	(paper "A4")
	(title_block
		(title "Bryce Canyon_SCC_16316-1_OCP.brd")
		(comment 1 "Bryce Canyon / footprints 1243-1250 of 1561")
	)
	(layers
		(0 "F.Cu" signal "TOP")
		(4 "In1.Cu" signal "L2GND")
		(6 "In2.Cu" signal "L3")
		(8 "In3.Cu" signal "L4VCC")
		(10 "In4.Cu" signal "L5VCC")
		(12 "In5.Cu" signal "L6")
		(14 "In6.Cu" signal "L7GND")
		(2 "B.Cu" signal "BOTTOM")
		(9 "F.Adhes" user "F.Adhesive")
		(11 "B.Adhes" user "B.Adhesive")
		(13 "F.Paste" user "Package Geometry/Pastemask Top")
		(15 "B.Paste" user "Package Geometry/Pastemask Bottom")
		(5 "F.SilkS" user "Ref Des/Silkscreen Top")
		(7 "B.SilkS" user "Ref Des/Silkscreen Bottom")
		(1 "F.Mask" user "Board Geometry/Soldermask Top")
		(3 "B.Mask" user "Board Geometry/Soldermask Bottom")
		(17 "Dwgs.User" user "User.Drawings")
		(19 "Cmts.User" user "User.Comments")
		(21 "Eco1.User" user "User.Eco1")
		(23 "Eco2.User" user "User.Eco2")
		(25 "Edge.Cuts" user "Board Geometry/Outline")
		(27 "Margin" user)
		(31 "F.CrtYd" user "Package Geometry/Place Bound Top")
		(29 "B.CrtYd" user "Package Geometry/Place Bound Bottom")
		(35 "F.Fab" user "Ref Des/Assembly Top")
		(33 "B.Fab" user "Ref Des/Assembly Bottom")
	)
	(footprint ""
		(layer "B.Cu")
		(at 73.025 -73.152 180)
		(property "Reference" "R287"
			(at 0 0 0)
			(layer "B.SilkS")
			(hide yes)
			(effects
				(font
					(size 1.27 1.27)
				)
				(justify mirror)
			)
		)
		(property "Value" "10KR2F-2-GP"
			(at -0.064008 -3.993896 180)
			(unlocked yes)
			(layer "B.Fab")
			(hide yes)
			(effects
				(font
					(size 1.016 1.016)
					(thickness 0.1524)
				)
				(justify mirror)
			)
		)
		(property "Device Type" "R402H16"
			(at -0.064008 -5.517896 180)
			(unlocked yes)
			(layer "B.Fab")
			(hide yes)
			(effects
				(font
					(size 1.016 1.016)
					(thickness 0.1524)
				)
				(justify mirror)
			)
		)
		(duplicate_pad_numbers_are_jumpers no)
		(fp_line
			(start 0.508 -0.9398)
			(end 0.508 0.9398)
			(stroke
				(width 0.1524)
				(type default)
			)
			(layer "B.SilkS")
		)
		(fp_line
			(start -0.508 -0.9398)
			(end 0.508 -0.9398)
			(stroke
				(width 0.1524)
				(type default)
			)
			(layer "B.SilkS")
		)
		(fp_rect
			(start 0.508 0.9398)
			(end -0.508 -0.9398)
			(stroke
				(width 0)
				(type default)
			)
			(fill no)
			(layer "B.CrtYd")
		)
		(fp_rect
			(start 0.508 0.9398)
			(end -0.508 -0.9398)
			(stroke
				(width 0)
				(type default)
			)
			(fill no)
			(layer "B.Fab")
		)
		(pad "1" smd custom
			(at 0 -0.4445)
			(size 0.1397 0.1397)
			(layers "B.Cu" "B.Mask" "B.Paste")
			(net "EXP_BYTE_N")
			(options
				(clearance outline)
				(anchor circle)
			)
			(primitives
				(gr_poly
					(pts
						(arc
							(start -0.1778 0.2794)
							(mid -0.249642 0.249642)
							(end -0.2794 0.1778)
						)
						(arc
							(start -0.2794 -0.1778)
							(mid -0.249642 -0.249642)
							(end -0.1778 -0.2794)
						)
						(arc
							(start 0.1778 -0.2794)
							(mid 0.249642 -0.249642)
							(end 0.2794 -0.1778)
						)
						(arc
							(start 0.2794 0.1778)
							(mid 0.249642 0.249642)
							(end 0.1778 0.2794)
						)
					)
					(width 0)
					(fill yes)
				)
			)
		)
		(pad "2" smd custom
			(at 0 0.4445)
			(size 0.1397 0.1397)
			(layers "B.Cu" "B.Mask" "B.Paste")
			(net "GND")
			(options
				(clearance outline)
				(anchor circle)
			)
			(primitives
				(gr_poly
					(pts
						(arc
							(start -0.1778 0.2794)
							(mid -0.249642 0.249642)
							(end -0.2794 0.1778)
						)
						(arc
							(start -0.2794 -0.1778)
							(mid -0.249642 -0.249642)
							(end -0.1778 -0.2794)
						)
						(arc
							(start 0.1778 -0.2794)
							(mid 0.249642 -0.249642)
							(end 0.2794 -0.1778)
						)
						(arc
							(start 0.2794 0.1778)
							(mid 0.249642 0.249642)
							(end 0.1778 0.2794)
						)
					)
					(width 0)
					(fill yes)
				)
			)
		)
	)
	(footprint ""
		(layer "B.Cu")
		(at 70.485 -60.833 90)
		(property "Reference" "L8"
			(at 0 0 90)
			(layer "B.SilkS")
			(hide yes)
			(effects
				(font
					(size 1.27 1.27)
				)
				(justify mirror)
			)
		)
		(property "Value" "MPZ2012S300AT-GP"
			(at 0 -4.2418 90)
			(unlocked yes)
			(layer "B.Fab")
			(hide yes)
			(effects
				(font
					(size 1.016 1.016)
					(thickness 0.1524)
				)
				(justify mirror)
			)
		)
		(property "Device Type" "L805H42"
			(at 0 -5.7912 90)
			(unlocked yes)
			(layer "B.Fab")
			(hide yes)
			(effects
				(font
					(size 1.016 1.016)
					(thickness 0.1524)
				)
				(justify mirror)
			)
		)
		(duplicate_pad_numbers_are_jumpers no)
		(fp_line
			(start 0.889 -1.7018)
			(end -0.889 -1.7018)
			(stroke
				(width 0.1524)
				(type default)
			)
			(layer "B.SilkS")
		)
		(fp_line
			(start -0.889 -1.7018)
			(end -0.889 1.7018)
			(stroke
				(width 0.1524)
				(type default)
			)
			(layer "B.SilkS")
		)
		(fp_line
			(start 0.889 1.7018)
			(end 0.889 -1.7018)
			(stroke
				(width 0.1524)
				(type default)
			)
			(layer "B.SilkS")
		)
		(fp_line
			(start -0.889 1.7018)
			(end 0.889 1.7018)
			(stroke
				(width 0.1524)
				(type default)
			)
			(layer "B.SilkS")
		)
		(fp_rect
			(start 0.9652 1.778)
			(end -0.9652 -1.778)
			(stroke
				(width 0)
				(type default)
			)
			(fill no)
			(layer "B.CrtYd")
		)
		(fp_rect
			(start 0.9652 1.778)
			(end -0.9652 -1.778)
			(stroke
				(width 0)
				(type default)
			)
			(fill no)
			(layer "B.Fab")
		)
		(pad "1" smd rect
			(at 0 -0.9652 270)
			(size 1.397 1.143)
			(layers "B.Cu" "B.Mask" "B.Paste")
			(net "P0V9")
		)
		(pad "2" smd rect
			(at 0 0.9652 270)
			(size 1.397 1.143)
			(layers "B.Cu" "B.Mask" "B.Paste")
			(net "GB_VDDA")
		)
	)
	(footprint ""
		(layer "B.Cu")
		(at 188.8236 -35.3314 90)
		(property "Reference" "TP96"
			(at 0 0 90)
			(layer "B.SilkS")
			(hide yes)
			(effects
				(font
					(size 1.27 1.27)
				)
				(justify mirror)
			)
		)
		(property "Value" "TPAD28-2-GP"
			(at 0.0127 -1.6637 90)
			(unlocked yes)
			(layer "B.Fab")
			(hide yes)
			(effects
				(font
					(size 1.016 1.016)
					(thickness 0.1524)
				)
				(justify mirror)
			)
		)
		(property "Device Type" "TPAD28"
			(at 0.0127 -3.1877 90)
			(unlocked yes)
			(layer "B.Fab")
			(hide yes)
			(effects
				(font
					(size 1.016 1.016)
					(thickness 0.1524)
				)
				(justify mirror)
			)
		)
		(duplicate_pad_numbers_are_jumpers no)
		(fp_poly
			(pts
				(arc
					(start 0 0.3556)
					(mid 0 -0.3556)
					(end 0 0.3556)
				)
			)
			(stroke
				(width 0)
				(type default)
			)
			(fill no)
			(layer "B.CrtYd")
		)
		(fp_poly
			(pts
				(arc
					(start 0 0.6096)
					(mid 0 -0.6096)
					(end 0 0.6096)
				)
			)
			(stroke
				(width 0)
				(type default)
			)
			(fill no)
			(layer "B.Fab")
		)
		(pad "1" smd circle
			(at 0 0 270)
			(size 0.7112 0.7112)
			(layers "B.Cu" "B.Mask" "B.Paste")
			(net "IOC_GPIO_35")
		)
	)
	(footprint ""
		(layer "B.Cu")
		(at 137.4648 -69.342 -90)
		(property "Reference" "C16"
			(at 0 0 90)
			(layer "B.SilkS")
			(hide yes)
			(effects
				(font
					(size 1.27 1.27)
				)
				(justify mirror)
			)
		)
		(property "Value" "SCD01U16V1KX-GP"
			(at 2.8321 -1.7399 270)
			(unlocked yes)
			(layer "B.Fab")
			(hide yes)
			(effects
				(font
					(size 1.016 1.016)
					(thickness 0.1524)
				)
				(justify mirror)
			)
		)
		(property "Device Type" "C0201H13"
			(at 2.8321 -3.2639 270)
			(unlocked yes)
			(layer "B.Fab")
			(hide yes)
			(effects
				(font
					(size 1.016 1.016)
					(thickness 0.1524)
				)
				(justify mirror)
			)
		)
		(duplicate_pad_numbers_are_jumpers no)
		(fp_rect
			(start 0.2794 0.6477)
			(end -0.2794 -0.6477)
			(stroke
				(width 0)
				(type default)
			)
			(fill no)
			(layer "B.CrtYd")
		)
		(fp_rect
			(start 0.2794 0.6477)
			(end -0.2794 -0.6477)
			(stroke
				(width 0)
				(type default)
			)
			(fill no)
			(layer "B.Fab")
		)
		(pad "1" smd custom
			(at 0 -0.2794 90)
			(size 0.0762 0.0762)
			(layers "B.Cu" "B.Mask" "B.Paste")
			(net "PHY_DPB_TO_SCC_4_DN")
			(options
				(clearance outline)
				(anchor circle)
			)
			(primitives
				(gr_poly
					(pts
						(arc
							(start 0.1524 0.127)
							(mid 0.137521 0.162921)
							(end 0.1016 0.1778)
						)
						(arc
							(start -0.1016 0.1778)
							(mid -0.137521 0.162921)
							(end -0.1524 0.127)
						)
						(arc
							(start -0.1524 -0.127)
							(mid -0.137521 -0.162921)
							(end -0.1016 -0.1778)
						)
						(arc
							(start 0.1016 -0.1778)
							(mid 0.137521 -0.162921)
							(end 0.1524 -0.127)
						)
					)
					(width 0)
					(fill yes)
				)
			)
		)
		(pad "2" smd custom
			(at 0 0.2794 90)
			(size 0.0762 0.0762)
			(layers "B.Cu" "B.Mask" "B.Paste")
			(net "PHY_DPB_TO_SCC_C_4_DN")
			(options
				(clearance outline)
				(anchor circle)
			)
			(primitives
				(gr_poly
					(pts
						(arc
							(start 0.1524 0.127)
							(mid 0.137521 0.162921)
							(end 0.1016 0.1778)
						)
						(arc
							(start -0.1016 0.1778)
							(mid -0.137521 0.162921)
							(end -0.1524 0.127)
						)
						(arc
							(start -0.1524 -0.127)
							(mid -0.137521 -0.162921)
							(end -0.1016 -0.1778)
						)
						(arc
							(start 0.1016 -0.1778)
							(mid 0.137521 -0.162921)
							(end 0.1524 -0.127)
						)
					)
					(width 0)
					(fill yes)
				)
			)
		)
	)
	(footprint ""
		(layer "B.Cu")
		(at 166.751 -64.008 90)
		(property "Reference" "C351"
			(at 0 0 90)
			(layer "B.SilkS")
			(hide yes)
			(effects
				(font
					(size 1.27 1.27)
				)
				(justify mirror)
			)
		)
		(property "Value" "SC22U6D3V3MX-9-GP-U"
			(at 0 -2.8194 90)
			(unlocked yes)
			(layer "B.Fab")
			(hide yes)
			(effects
				(font
					(size 1.016 1.016)
					(thickness 0.1524)
				)
				(justify mirror)
			)
		)
		(property "Device Type" "C603H40"
			(at 0 -4.3434 90)
			(unlocked yes)
			(layer "B.Fab")
			(hide yes)
			(effects
				(font
					(size 1.016 1.016)
					(thickness 0.1524)
				)
				(justify mirror)
			)
		)
		(duplicate_pad_numbers_are_jumpers no)
		(fp_line
			(start -0.508 0)
			(end 0.508 0)
			(stroke
				(width 0.2032)
				(type default)
			)
			(layer "B.SilkS")
		)
		(fp_rect
			(start 0.5842 1.3335)
			(end -0.5842 -1.3335)
			(stroke
				(width 0)
				(type default)
			)
			(fill no)
			(layer "B.CrtYd")
		)
		(fp_rect
			(start 0.5842 1.3335)
			(end -0.5842 -1.3335)
			(stroke
				(width 0)
				(type default)
			)
			(fill no)
			(layer "B.Fab")
		)
		(pad "1" smd custom
			(at 0 -0.762 270)
			(size 0.2159 0.2159)
			(layers "B.Cu" "B.Mask" "B.Paste")
			(net "HM40ADC_VDDA")
			(options
				(clearance outline)
				(anchor circle)
			)
			(primitives
				(gr_poly
					(pts
						(arc
							(start -0.3302 0.4318)
							(mid -0.402042 0.402042)
							(end -0.4318 0.3302)
						)
						(arc
							(start -0.4318 -0.3302)
							(mid -0.402042 -0.402042)
							(end -0.3302 -0.4318)
						)
						(arc
							(start 0.3302 -0.4318)
							(mid 0.402042 -0.402042)
							(end 0.4318 -0.3302)
						)
						(arc
							(start 0.4318 0.3302)
							(mid 0.402042 0.402042)
							(end 0.3302 0.4318)
						)
					)
					(width 0)
					(fill yes)
				)
			)
		)
		(pad "2" smd custom
			(at 0 0.762 270)
			(size 0.2159 0.2159)
			(layers "B.Cu" "B.Mask" "B.Paste")
			(net "GND")
			(options
				(clearance outline)
				(anchor circle)
			)
			(primitives
				(gr_poly
					(pts
						(arc
							(start -0.3302 0.4318)
							(mid -0.402042 0.402042)
							(end -0.4318 0.3302)
						)
						(arc
							(start -0.4318 -0.3302)
							(mid -0.402042 -0.402042)
							(end -0.3302 -0.4318)
						)
						(arc
							(start 0.3302 -0.4318)
							(mid 0.402042 -0.402042)
							(end 0.4318 -0.3302)
						)
						(arc
							(start 0.4318 0.3302)
							(mid 0.402042 0.402042)
							(end 0.3302 0.4318)
						)
					)
					(width 0)
					(fill yes)
				)
			)
		)
	)
	(footprint ""
		(layer "B.Cu")
		(at 122.4788 -64.4906 -90)
		(property "Reference" "C246"
			(at 0 0 90)
			(layer "B.SilkS")
			(hide yes)
			(effects
				(font
					(size 1.27 1.27)
				)
				(justify mirror)
			)
		)
		(property "Value" "SCD1U6D3V1KX-GP"
			(at 2.8321 -1.7399 270)
			(unlocked yes)
			(layer "B.Fab")
			(hide yes)
			(effects
				(font
					(size 1.016 1.016)
					(thickness 0.1524)
				)
				(justify mirror)
			)
		)
		(property "Device Type" "C0201H13"
			(at 2.8321 -3.2639 270)
			(unlocked yes)
			(layer "B.Fab")
			(hide yes)
			(effects
				(font
					(size 1.016 1.016)
					(thickness 0.1524)
				)
				(justify mirror)
			)
		)
		(duplicate_pad_numbers_are_jumpers no)
		(fp_rect
			(start 0.2794 0.6477)
			(end -0.2794 -0.6477)
			(stroke
				(width 0)
				(type default)
			)
			(fill no)
			(layer "B.CrtYd")
		)
		(fp_rect
			(start 0.2794 0.6477)
			(end -0.2794 -0.6477)
			(stroke
				(width 0)
				(type default)
			)
			(fill no)
			(layer "B.Fab")
		)
		(pad "1" smd custom
			(at 0 -0.2794 90)
			(size 0.0762 0.0762)
			(layers "B.Cu" "B.Mask" "B.Paste")
			(net "GB_VDDA")
			(options
				(clearance outline)
				(anchor circle)
			)
			(primitives
				(gr_poly
					(pts
						(arc
							(start 0.1524 0.127)
							(mid 0.137521 0.162921)
							(end 0.1016 0.1778)
						)
						(arc
							(start -0.1016 0.1778)
							(mid -0.137521 0.162921)
							(end -0.1524 0.127)
						)
						(arc
							(start -0.1524 -0.127)
							(mid -0.137521 -0.162921)
							(end -0.1016 -0.1778)
						)
						(arc
							(start 0.1016 -0.1778)
							(mid 0.137521 -0.162921)
							(end 0.1524 -0.127)
						)
					)
					(width 0)
					(fill yes)
				)
			)
		)
		(pad "2" smd custom
			(at 0 0.2794 90)
			(size 0.0762 0.0762)
			(layers "B.Cu" "B.Mask" "B.Paste")
			(net "GND")
			(options
				(clearance outline)
				(anchor circle)
			)
			(primitives
				(gr_poly
					(pts
						(arc
							(start 0.1524 0.127)
							(mid 0.137521 0.162921)
							(end 0.1016 0.1778)
						)
						(arc
							(start -0.1016 0.1778)
							(mid -0.137521 0.162921)
							(end -0.1524 0.127)
						)
						(arc
							(start -0.1524 -0.127)
							(mid -0.137521 -0.162921)
							(end -0.1016 -0.1778)
						)
						(arc
							(start 0.1016 -0.1778)
							(mid 0.137521 -0.162921)
							(end 0.1524 -0.127)
						)
					)
					(width 0)
					(fill yes)
				)
			)
		)
	)
	(footprint ""
		(layer "B.Cu")
		(at 111.252 -61.488066)
		(property "Reference" "C224"
			(at 0 0 0)
			(layer "B.SilkS")
			(hide yes)
			(effects
				(font
					(size 1.27 1.27)
				)
				(justify mirror)
			)
		)
		(property "Value" "SCD1U16V2KX-3GP"
			(at -1.1811 -2.7051 0)
			(unlocked yes)
			(layer "B.Fab")
			(hide yes)
			(effects
				(font
					(size 1.016 1.016)
					(thickness 0.1524)
				)
				(justify mirror)
			)
		)
		(property "Device Type" "C402H22"
			(at -1.1811 -4.2291 0)
			(unlocked yes)
			(layer "B.Fab")
			(hide yes)
			(effects
				(font
					(size 1.016 1.016)
					(thickness 0.1524)
				)
				(justify mirror)
			)
		)
		(duplicate_pad_numbers_are_jumpers no)
		(fp_rect
			(start 0.4318 0.9525)
			(end -0.4318 -0.9525)
			(stroke
				(width 0)
				(type default)
			)
			(fill no)
			(layer "B.CrtYd")
		)
		(fp_rect
			(start 0.4318 0.9525)
			(end -0.4318 -0.9525)
			(stroke
				(width 0)
				(type default)
			)
			(fill no)
			(layer "B.Fab")
		)
		(pad "1" smd custom
			(at 0 -0.4445 180)
			(size 0.1524 0.1524)
			(layers "B.Cu" "B.Mask" "B.Paste")
			(net "GB_VDDH")
			(options
				(clearance outline)
				(anchor circle)
			)
			(primitives
				(gr_poly
					(pts
						(arc
							(start 0.3048 0.2032)
							(mid 0.275042 0.275042)
							(end 0.2032 0.3048)
						)
						(arc
							(start -0.2032 0.3048)
							(mid -0.275042 0.275042)
							(end -0.3048 0.2032)
						)
						(arc
							(start -0.3048 -0.2032)
							(mid -0.275042 -0.275042)
							(end -0.2032 -0.3048)
						)
						(arc
							(start 0.2032 -0.3048)
							(mid 0.275042 -0.275042)
							(end 0.3048 -0.2032)
						)
					)
					(width 0)
					(fill yes)
				)
			)
		)
		(pad "2" smd custom
			(at 0 0.4445 180)
			(size 0.1524 0.1524)
			(layers "B.Cu" "B.Mask" "B.Paste")
			(net "GND")
			(options
				(clearance outline)
				(anchor circle)
			)
			(primitives
				(gr_poly
					(pts
						(arc
							(start 0.3048 0.2032)
							(mid 0.275042 0.275042)
							(end 0.2032 0.3048)
						)
						(arc
							(start -0.2032 0.3048)
							(mid -0.275042 0.275042)
							(end -0.3048 0.2032)
						)
						(arc
							(start -0.3048 -0.2032)
							(mid -0.275042 -0.275042)
							(end -0.2032 -0.3048)
						)
						(arc
							(start 0.2032 -0.3048)
							(mid 0.275042 -0.275042)
							(end 0.3048 -0.2032)
						)
					)
					(width 0)
					(fill yes)
				)
			)
		)
	)
	(footprint ""
		(layer "B.Cu")
		(at 183.9468 -28.1178 90)
		(property "Reference" "TP60"
			(at 0 0 90)
			(layer "B.SilkS")
			(hide yes)
			(effects
				(font
					(size 1.27 1.27)
				)
				(justify mirror)
			)
		)
		(property "Value" "TPAD28-2-GP"
			(at 0.0127 -1.6637 90)
			(unlocked yes)
			(layer "B.Fab")
			(hide yes)
			(effects
				(font
					(size 1.016 1.016)
					(thickness 0.1524)
				)
				(justify mirror)
			)
		)
		(property "Device Type" "TPAD28"
			(at 0.0127 -3.1877 90)
			(unlocked yes)
			(layer "B.Fab")
			(hide yes)
			(effects
				(font
					(size 1.016 1.016)
					(thickness 0.1524)
				)
				(justify mirror)
			)
		)
		(duplicate_pad_numbers_are_jumpers no)
		(fp_poly
			(pts
				(arc
					(start 0 0.3556)
					(mid 0 -0.3556)
					(end 0 0.3556)
				)
			)
			(stroke
				(width 0)
				(type default)
			)
			(fill no)
			(layer "B.CrtYd")
		)
		(fp_poly
			(pts
				(arc
					(start 0 0.6096)
					(mid 0 -0.6096)
					(end 0 0.6096)
				)
			)
			(stroke
				(width 0)
				(type default)
			)
			(fill no)
			(layer "B.Fab")
		)
		(pad "1" smd circle
			(at 0 0 270)
			(size 0.7112 0.7112)
			(layers "B.Cu" "B.Mask" "B.Paste")
			(net "IOC_GPIO_6")
		)
	)
)
